(kicad_pcb
	(version 20260206)
	(generator "pcbnew")
	(generator_version "10.0")
	(general
		(thickness 1.6)
		(legacy_teardrops no)
	)
	(paper "A4")
	(title_block
		(title "04192023_DAF0TMB3IC0_F0TG_MB_C_brd_V02_OCP.brd")
		(comment 1 "Grand Teton / footprints 2371-2377 of 8354")
	)
	(layers
		(0 "F.Cu" signal "TOP")
		(4 "In1.Cu" signal "GND")
		(6 "In2.Cu" signal "IN1")
		(8 "In3.Cu" signal "GND1")
		(10 "In4.Cu" signal "IN2")
		(12 "In5.Cu" signal "GND2")
		(14 "In6.Cu" signal "IN3")
		(16 "In7.Cu" signal "GND3")
		(18 "In8.Cu" signal "VCC")
		(20 "In9.Cu" signal "VCC1")
		(22 "In10.Cu" signal "GND4")
		(24 "In11.Cu" signal "IN4")
		(26 "In12.Cu" signal "GND5")
		(28 "In13.Cu" signal "IN5")
		(30 "In14.Cu" signal "GND6")
		(32 "In15.Cu" signal "IN6")
		(34 "In16.Cu" signal "GND7")
		(2 "B.Cu" signal "BOTTOM")
		(9 "F.Adhes" user "F.Adhesive")
		(11 "B.Adhes" user "B.Adhesive")
		(13 "F.Paste" user "Package Geometry/Pastemask Top")
		(15 "B.Paste" user "Package Geometry/Pastemask Bottom")
		(5 "F.SilkS" user "Ref Des/Silkscreen Top")
		(7 "B.SilkS" user "Ref Des/Silkscreen Bottom")
		(1 "F.Mask" user "Board Geometry/Soldermask Top")
		(3 "B.Mask" user "Board Geometry/Soldermask Bottom")
		(17 "Dwgs.User" user "User.Drawings")
		(19 "Cmts.User" user "User.Comments")
		(21 "Eco1.User" user "User.Eco1")
		(23 "Eco2.User" user "User.Eco2")
		(25 "Edge.Cuts" user "Board Geometry/Outline")
		(27 "Margin" user)
		(31 "F.CrtYd" user "Package Geometry/Place Bound Top")
		(29 "B.CrtYd" user "Package Geometry/Place Bound Bottom")
		(35 "F.Fab" user "Ref Des/Assembly Top")
		(33 "B.Fab" user "Ref Des/Assembly Bottom")
	)
	(footprint ""
		(layer "F.Cu")
		(at 418.852096 -357.688134 -90)
		(property "Reference" "PR37"
			(at 0 0 270)
			(layer "F.SilkS")
			(hide yes)
			(effects
				(font
					(size 1.27 1.27)
				)
			)
		)
		(property "Value" ""
			(at 0 0 270)
			(layer "F.Fab")
			(effects
				(font
					(size 1.27 1.27)
				)
			)
		)
		(duplicate_pad_numbers_are_jumpers no)
		(fp_line
			(start -0.7874 0.4064)
			(end -0.7874 -0.4064)
			(stroke
				(width 0.1524)
				(type default)
			)
			(layer "F.SilkS")
		)
		(fp_line
			(start 0.7874 0.4064)
			(end -0.7874 0.4064)
			(stroke
				(width 0.1524)
				(type default)
			)
			(layer "F.SilkS")
		)
		(fp_line
			(start -0.7874 -0.4064)
			(end 0.7874 -0.4064)
			(stroke
				(width 0.1524)
				(type default)
			)
			(layer "F.SilkS")
		)
		(fp_line
			(start 0.7874 -0.4064)
			(end 0.7874 0.4064)
			(stroke
				(width 0.1524)
				(type default)
			)
			(layer "F.SilkS")
		)
		(fp_line
			(start -0.67945 0.3048)
			(end -0.67945 -0.305054)
			(stroke
				(width 0.1)
				(type default)
			)
			(layer "F.Fab")
		)
		(fp_line
			(start -0.12065 0.3048)
			(end -0.67945 0.3048)
			(stroke
				(width 0.1)
				(type default)
			)
			(layer "F.Fab")
		)
		(fp_line
			(start 0.120396 0.3048)
			(end 0.120396 0.2794)
			(stroke
				(width 0.1)
				(type default)
			)
			(layer "F.Fab")
		)
		(fp_line
			(start 0.67945 0.3048)
			(end 0.120396 0.3048)
			(stroke
				(width 0.1)
				(type default)
			)
			(layer "F.Fab")
		)
		(fp_line
			(start -0.12065 0.2794)
			(end -0.12065 0.3048)
			(stroke
				(width 0.1)
				(type default)
			)
			(layer "F.Fab")
		)
		(fp_line
			(start 0.120396 0.2794)
			(end -0.12065 0.2794)
			(stroke
				(width 0.1)
				(type default)
			)
			(layer "F.Fab")
		)
		(fp_line
			(start -0.12065 -0.2794)
			(end 0.12065 -0.2794)
			(stroke
				(width 0.1)
				(type default)
			)
			(layer "F.Fab")
		)
		(fp_line
			(start 0.12065 -0.2794)
			(end 0.12065 -0.3048)
			(stroke
				(width 0.1)
				(type default)
			)
			(layer "F.Fab")
		)
		(fp_line
			(start 0.12065 -0.3048)
			(end 0.67945 -0.3048)
			(stroke
				(width 0.1)
				(type default)
			)
			(layer "F.Fab")
		)
		(fp_line
			(start 0.67945 -0.3048)
			(end 0.67945 0.3048)
			(stroke
				(width 0.1)
				(type default)
			)
			(layer "F.Fab")
		)
		(fp_line
			(start -0.67945 -0.305054)
			(end -0.12065 -0.305054)
			(stroke
				(width 0.1)
				(type default)
			)
			(layer "F.Fab")
		)
		(fp_line
			(start -0.12065 -0.305054)
			(end -0.12065 -0.2794)
			(stroke
				(width 0.1)
				(type default)
			)
			(layer "F.Fab")
		)
		(pad "1" smd circle
			(at -0.40005 0 270)
			(size 0 0)
			(layers "F.Cu" "F.Mask" "F.Paste")
			(net "NC_PVDD11_S3_P0_IMON3")
		)
		(pad "2" smd circle
			(at 0.40005 0 270)
			(size 0 0)
			(layers "F.Cu" "F.Mask" "F.Paste")
			(net "GND")
		)
	)
	(footprint ""
		(layer "F.Cu")
		(at 183.007 -137.632948 90)
		(property "Reference" "R1286"
			(at 0 0 90)
			(layer "F.SilkS")
			(hide yes)
			(effects
				(font
					(size 1.27 1.27)
				)
			)
		)
		(property "Value" ""
			(at 0 0 90)
			(layer "F.Fab")
			(effects
				(font
					(size 1.27 1.27)
				)
			)
		)
		(duplicate_pad_numbers_are_jumpers no)
		(fp_line
			(start 0.7874 -0.4064)
			(end 0.7874 0.4064)
			(stroke
				(width 0.1524)
				(type default)
			)
			(layer "F.SilkS")
		)
		(fp_line
			(start -0.7874 -0.4064)
			(end 0.7874 -0.4064)
			(stroke
				(width 0.1524)
				(type default)
			)
			(layer "F.SilkS")
		)
		(fp_line
			(start 0.7874 0.4064)
			(end -0.7874 0.4064)
			(stroke
				(width 0.1524)
				(type default)
			)
			(layer "F.SilkS")
		)
		(fp_line
			(start -0.7874 0.4064)
			(end -0.7874 -0.4064)
			(stroke
				(width 0.1524)
				(type default)
			)
			(layer "F.SilkS")
		)
		(fp_line
			(start -0.12065 -0.305054)
			(end -0.12065 -0.2794)
			(stroke
				(width 0.1)
				(type default)
			)
			(layer "F.Fab")
		)
		(fp_line
			(start -0.67945 -0.305054)
			(end -0.12065 -0.305054)
			(stroke
				(width 0.1)
				(type default)
			)
			(layer "F.Fab")
		)
		(fp_line
			(start 0.67945 -0.3048)
			(end 0.67945 0.3048)
			(stroke
				(width 0.1)
				(type default)
			)
			(layer "F.Fab")
		)
		(fp_line
			(start 0.12065 -0.3048)
			(end 0.67945 -0.3048)
			(stroke
				(width 0.1)
				(type default)
			)
			(layer "F.Fab")
		)
		(fp_line
			(start 0.12065 -0.2794)
			(end 0.12065 -0.3048)
			(stroke
				(width 0.1)
				(type default)
			)
			(layer "F.Fab")
		)
		(fp_line
			(start -0.12065 -0.2794)
			(end 0.12065 -0.2794)
			(stroke
				(width 0.1)
				(type default)
			)
			(layer "F.Fab")
		)
		(fp_line
			(start 0.120396 0.2794)
			(end -0.12065 0.2794)
			(stroke
				(width 0.1)
				(type default)
			)
			(layer "F.Fab")
		)
		(fp_line
			(start -0.12065 0.2794)
			(end -0.12065 0.3048)
			(stroke
				(width 0.1)
				(type default)
			)
			(layer "F.Fab")
		)
		(fp_line
			(start 0.67945 0.3048)
			(end 0.120396 0.3048)
			(stroke
				(width 0.1)
				(type default)
			)
			(layer "F.Fab")
		)
		(fp_line
			(start 0.120396 0.3048)
			(end 0.120396 0.2794)
			(stroke
				(width 0.1)
				(type default)
			)
			(layer "F.Fab")
		)
		(fp_line
			(start -0.12065 0.3048)
			(end -0.67945 0.3048)
			(stroke
				(width 0.1)
				(type default)
			)
			(layer "F.Fab")
		)
		(fp_line
			(start -0.67945 0.3048)
			(end -0.67945 -0.305054)
			(stroke
				(width 0.1)
				(type default)
			)
			(layer "F.Fab")
		)
		(pad "1" smd circle
			(at -0.40005 0 90)
			(size 0 0)
			(layers "F.Cu" "F.Mask" "F.Paste")
			(net "FM_P1_PCC1_N")
		)
		(pad "2" smd circle
			(at 0.40005 0 90)
			(size 0 0)
			(layers "F.Cu" "F.Mask" "F.Paste")
			(net "PVDD18_S5_P1")
		)
	)
	(footprint ""
		(layer "F.Cu")
		(at 421.047164 -17.624298 90)
		(property "Reference" "C1570"
			(at 0 0 90)
			(layer "F.SilkS")
			(hide yes)
			(effects
				(font
					(size 1.27 1.27)
				)
			)
		)
		(property "Value" ""
			(at 0 0 90)
			(layer "F.Fab")
			(effects
				(font
					(size 1.27 1.27)
				)
			)
		)
		(duplicate_pad_numbers_are_jumpers no)
		(fp_line
			(start 0.299974 -0.150114)
			(end 0.299974 0.150114)
			(stroke
				(width 0.1)
				(type default)
			)
			(layer "F.Fab")
		)
		(fp_line
			(start -0.299974 -0.150114)
			(end 0.299974 -0.150114)
			(stroke
				(width 0.1)
				(type default)
			)
			(layer "F.Fab")
		)
		(fp_line
			(start 0.299974 0.150114)
			(end -0.299974 0.150114)
			(stroke
				(width 0.1)
				(type default)
			)
			(layer "F.Fab")
		)
		(fp_line
			(start -0.299974 0.150114)
			(end -0.299974 -0.150114)
			(stroke
				(width 0.1)
				(type default)
			)
			(layer "F.Fab")
		)
		(pad "1" smd rect
			(at -0.2667 0 90)
			(size 0.3048 0.381)
			(layers "F.Cu" "F.Mask" "F.Paste")
			(net "P5E_CPU0_G3_TX_C_DN<4>")
		)
		(pad "2" smd rect
			(at 0.2667 0 90)
			(size 0.3048 0.381)
			(layers "F.Cu" "F.Mask" "F.Paste")
			(net "P5E_CPU0_G3_TX_DN<4>")
		)
	)
	(footprint ""
		(layer "F.Cu")
		(at 58.191654 -349.386398 90)
		(property "Reference" "PC399"
			(at 0 0 90)
			(layer "F.SilkS")
			(hide yes)
			(effects
				(font
					(size 1.27 1.27)
				)
			)
		)
		(property "Value" ""
			(at 0 0 90)
			(layer "F.Fab")
			(effects
				(font
					(size 1.27 1.27)
				)
			)
		)
		(duplicate_pad_numbers_are_jumpers no)
		(fp_line
			(start 0.7874 -0.4064)
			(end 0.7874 0.4064)
			(stroke
				(width 0.1524)
				(type default)
			)
			(layer "F.SilkS")
		)
		(fp_line
			(start -0.7874 -0.4064)
			(end 0.7874 -0.4064)
			(stroke
				(width 0.1524)
				(type default)
			)
			(layer "F.SilkS")
		)
		(fp_line
			(start 0.7874 0.4064)
			(end 0.397002 0.4064)
			(stroke
				(width 0.1524)
				(type default)
			)
			(layer "F.SilkS")
		)
		(fp_line
			(start -0.212598 0.4064)
			(end -0.7874 0.4064)
			(stroke
				(width 0.1524)
				(type default)
			)
			(layer "F.SilkS")
		)
		(fp_line
			(start -0.7874 0.4064)
			(end -0.7874 -0.4064)
			(stroke
				(width 0.1524)
				(type default)
			)
			(layer "F.SilkS")
		)
		(fp_line
			(start -0.12065 -0.305054)
			(end -0.12065 -0.2794)
			(stroke
				(width 0.1)
				(type default)
			)
			(layer "F.Fab")
		)
		(fp_line
			(start -0.67945 -0.305054)
			(end -0.12065 -0.305054)
			(stroke
				(width 0.1)
				(type default)
			)
			(layer "F.Fab")
		)
		(fp_line
			(start 0.67945 -0.3048)
			(end 0.67945 0.3048)
			(stroke
				(width 0.1)
				(type default)
			)
			(layer "F.Fab")
		)
		(fp_line
			(start 0.12065 -0.3048)
			(end 0.67945 -0.3048)
			(stroke
				(width 0.1)
				(type default)
			)
			(layer "F.Fab")
		)
		(fp_line
			(start 0.12065 -0.2794)
			(end 0.12065 -0.3048)
			(stroke
				(width 0.1)
				(type default)
			)
			(layer "F.Fab")
		)
		(fp_line
			(start -0.12065 -0.2794)
			(end 0.12065 -0.2794)
			(stroke
				(width 0.1)
				(type default)
			)
			(layer "F.Fab")
		)
		(fp_line
			(start 0.120396 0.2794)
			(end -0.12065 0.2794)
			(stroke
				(width 0.1)
				(type default)
			)
			(layer "F.Fab")
		)
		(fp_line
			(start -0.12065 0.2794)
			(end -0.12065 0.3048)
			(stroke
				(width 0.1)
				(type default)
			)
			(layer "F.Fab")
		)
		(fp_line
			(start 0.67945 0.3048)
			(end 0.120396 0.3048)
			(stroke
				(width 0.1)
				(type default)
			)
			(layer "F.Fab")
		)
		(fp_line
			(start 0.120396 0.3048)
			(end 0.120396 0.2794)
			(stroke
				(width 0.1)
				(type default)
			)
			(layer "F.Fab")
		)
		(fp_line
			(start -0.12065 0.3048)
			(end -0.67945 0.3048)
			(stroke
				(width 0.1)
				(type default)
			)
			(layer "F.Fab")
		)
		(fp_line
			(start -0.67945 0.3048)
			(end -0.67945 -0.305054)
			(stroke
				(width 0.1)
				(type default)
			)
			(layer "F.Fab")
		)
		(pad "1" smd circle
			(at -0.40005 0 90)
			(size 0 0)
			(layers "F.Cu" "F.Mask" "F.Paste")
			(net "PVDDCR_CPU1_P1_VCC4")
		)
		(pad "2" smd circle
			(at 0.40005 0 90)
			(size 0 0)
			(layers "F.Cu" "F.Mask" "F.Paste")
			(net "GND")
		)
	)
	(footprint ""
		(layer "F.Cu")
		(at 443.347602 -429.37811 -90)
		(property "Reference" "R647"
			(at 0 0 270)
			(layer "F.SilkS")
			(hide yes)
			(effects
				(font
					(size 1.27 1.27)
				)
			)
		)
		(property "Value" ""
			(at 0 0 270)
			(layer "F.Fab")
			(effects
				(font
					(size 1.27 1.27)
				)
			)
		)
		(duplicate_pad_numbers_are_jumpers no)
		(fp_line
			(start -0.7874 0.4064)
			(end -0.7874 -0.4064)
			(stroke
				(width 0.1524)
				(type default)
			)
			(layer "F.SilkS")
		)
		(fp_line
			(start 0.7874 0.4064)
			(end -0.7874 0.4064)
			(stroke
				(width 0.1524)
				(type default)
			)
			(layer "F.SilkS")
		)
		(fp_line
			(start -0.7874 -0.4064)
			(end 0.7874 -0.4064)
			(stroke
				(width 0.1524)
				(type default)
			)
			(layer "F.SilkS")
		)
		(fp_line
			(start 0.7874 -0.4064)
			(end 0.7874 0.4064)
			(stroke
				(width 0.1524)
				(type default)
			)
			(layer "F.SilkS")
		)
		(fp_line
			(start -0.67945 0.3048)
			(end -0.67945 -0.305054)
			(stroke
				(width 0.1)
				(type default)
			)
			(layer "F.Fab")
		)
		(fp_line
			(start -0.12065 0.3048)
			(end -0.67945 0.3048)
			(stroke
				(width 0.1)
				(type default)
			)
			(layer "F.Fab")
		)
		(fp_line
			(start 0.120396 0.3048)
			(end 0.120396 0.2794)
			(stroke
				(width 0.1)
				(type default)
			)
			(layer "F.Fab")
		)
		(fp_line
			(start 0.67945 0.3048)
			(end 0.120396 0.3048)
			(stroke
				(width 0.1)
				(type default)
			)
			(layer "F.Fab")
		)
		(fp_line
			(start -0.12065 0.2794)
			(end -0.12065 0.3048)
			(stroke
				(width 0.1)
				(type default)
			)
			(layer "F.Fab")
		)
		(fp_line
			(start 0.120396 0.2794)
			(end -0.12065 0.2794)
			(stroke
				(width 0.1)
				(type default)
			)
			(layer "F.Fab")
		)
		(fp_line
			(start -0.12065 -0.2794)
			(end 0.12065 -0.2794)
			(stroke
				(width 0.1)
				(type default)
			)
			(layer "F.Fab")
		)
		(fp_line
			(start 0.12065 -0.2794)
			(end 0.12065 -0.3048)
			(stroke
				(width 0.1)
				(type default)
			)
			(layer "F.Fab")
		)
		(fp_line
			(start 0.12065 -0.3048)
			(end 0.67945 -0.3048)
			(stroke
				(width 0.1)
				(type default)
			)
			(layer "F.Fab")
		)
		(fp_line
			(start 0.67945 -0.3048)
			(end 0.67945 0.3048)
			(stroke
				(width 0.1)
				(type default)
			)
			(layer "F.Fab")
		)
		(fp_line
			(start -0.67945 -0.305054)
			(end -0.12065 -0.305054)
			(stroke
				(width 0.1)
				(type default)
			)
			(layer "F.Fab")
		)
		(fp_line
			(start -0.12065 -0.305054)
			(end -0.12065 -0.2794)
			(stroke
				(width 0.1)
				(type default)
			)
			(layer "F.Fab")
		)
		(pad "1" smd circle
			(at -0.40005 0 270)
			(size 0 0)
			(layers "F.Cu" "F.Mask" "F.Paste")
			(net "P0V9_RETIMER_CPU0_PMSDA")
		)
		(pad "2" smd circle
			(at 0.40005 0 270)
			(size 0 0)
			(layers "F.Cu" "F.Mask" "F.Paste")
			(net "P0V9_RETIMER_CPU0_PMSDA_R")
		)
	)
	(footprint ""
		(layer "F.Cu")
		(at 464.799934 -22.29993)
		(property "Reference" "H96"
			(at -5.137658 -5.653532 0)
			(unlocked yes)
			(layer "F.SilkS")
			(effects
				(font
					(size 0.7874 0.5842)
					(thickness 0.1524)
				)
				(justify left)
			)
		)
		(property "Value" ""
			(at 0 0 0)
			(layer "F.Fab")
			(effects
				(font
					(size 1.27 1.27)
				)
			)
		)
		(duplicate_pad_numbers_are_jumpers no)
		(pad "1" thru_hole circle
			(at 0 0)
			(size 10.0076 10.0076)
			(drill 5.6134)
			(layers "*.Cu" "*.Mask")
			(remove_unused_layers no)
			(net "GND")
			(clearance -1.9431)
		)
	)
	(footprint ""
		(layer "F.Cu")
		(at 142.367 -121.285)
		(property "Reference" "R8124"
			(at 0 0 0)
			(layer "F.SilkS")
			(hide yes)
			(effects
				(font
					(size 1.27 1.27)
				)
			)
		)
		(property "Value" ""
			(at 0 0 0)
			(layer "F.Fab")
			(effects
				(font
					(size 1.27 1.27)
				)
			)
		)
		(duplicate_pad_numbers_are_jumpers no)
		(fp_line
			(start -0.7874 -0.4064)
			(end 0.7874 -0.4064)
			(stroke
				(width 0.1524)
				(type default)
			)
			(layer "F.SilkS")
		)
		(fp_line
			(start -0.7874 0.4064)
			(end -0.7874 -0.4064)
			(stroke
				(width 0.1524)
				(type default)
			)
			(layer "F.SilkS")
		)
		(fp_line
			(start 0.7874 -0.4064)
			(end 0.7874 0.4064)
			(stroke
				(width 0.1524)
				(type default)
			)
			(layer "F.SilkS")
		)
		(fp_line
			(start 0.7874 0.4064)
			(end -0.7874 0.4064)
			(stroke
				(width 0.1524)
				(type default)
			)
			(layer "F.SilkS")
		)
		(fp_line
			(start -0.67945 -0.305054)
			(end -0.12065 -0.305054)
			(stroke
				(width 0.1)
				(type default)
			)
			(layer "F.Fab")
		)
		(fp_line
			(start -0.67945 0.3048)
			(end -0.67945 -0.305054)
			(stroke
				(width 0.1)
				(type default)
			)
			(layer "F.Fab")
		)
		(fp_line
			(start -0.12065 -0.305054)
			(end -0.12065 -0.2794)
			(stroke
				(width 0.1)
				(type default)
			)
			(layer "F.Fab")
		)
		(fp_line
			(start -0.12065 -0.2794)
			(end 0.12065 -0.2794)
			(stroke
				(width 0.1)
				(type default)
			)
			(layer "F.Fab")
		)
		(fp_line
			(start -0.12065 0.2794)
			(end -0.12065 0.3048)
			(stroke
				(width 0.1)
				(type default)
			)
			(layer "F.Fab")
		)
		(fp_line
			(start -0.12065 0.3048)
			(end -0.67945 0.3048)
			(stroke
				(width 0.1)
				(type default)
			)
			(layer "F.Fab")
		)
		(fp_line
			(start 0.120396 0.2794)
			(end -0.12065 0.2794)
			(stroke
				(width 0.1)
				(type default)
			)
			(layer "F.Fab")
		)
		(fp_line
			(start 0.120396 0.3048)
			(end 0.120396 0.2794)
			(stroke
				(width 0.1)
				(type default)
			)
			(layer "F.Fab")
		)
		(fp_line
			(start 0.12065 -0.3048)
			(end 0.67945 -0.3048)
			(stroke
				(width 0.1)
				(type default)
			)
			(layer "F.Fab")
		)
		(fp_line
			(start 0.12065 -0.2794)
			(end 0.12065 -0.3048)
			(stroke
				(width 0.1)
				(type default)
			)
			(layer "F.Fab")
		)
		(fp_line
			(start 0.67945 -0.3048)
			(end 0.67945 0.3048)
			(stroke
				(width 0.1)
				(type default)
			)
			(layer "F.Fab")
		)
		(fp_line
			(start 0.67945 0.3048)
			(end 0.120396 0.3048)
			(stroke
				(width 0.1)
				(type default)
			)
			(layer "F.Fab")
		)
		(pad "1" smd circle
			(at -0.40005 0)
			(size 0 0)
			(layers "F.Cu" "F.Mask" "F.Paste")
			(net "IRQ_UV_DETECT_R2_N")
		)
		(pad "2" smd circle
			(at 0.40005 0)
			(size 0 0)
			(layers "F.Cu" "F.Mask" "F.Paste")
			(net "IRQ_UV_DETECT_N")
		)
	)
)
